# T6G (Grand Teton) — schematic netlist excerpt (pin names and nets, part order shuffled) for the footprints in the layout excerpt that follows; sources: Cadence DE-HDL packaged netlist, KiCad conversion of 04192023_DAF0TMB3IC0_F0TG_MB_C_brd_V02_OCP.brd

PR228  Q_RES  49.9 1% CHIP  pkg 0402LF  page 217 : A = VSENSE_PVDDCR_CPU1_P1_DP ; B = PVDDCR_CPU1_P1
R791  Q_RES  4.7K 5% CHIP  pkg 0201LF  page 331 : A = TEST2_RT_CPU1_P1 ; B = GND
R2982  Q_RES  0 5% CHIP  pkg 0402LF  page 245 : A = SMB_IOEXP_3V3AUX_SCL ; B = SMB_IOEXP_3V3AUX_SCL_R1

(kicad_pcb
	(version 20260206)
	(generator "pcbnew")
	(generator_version "10.0")
	(general
		(thickness 1.6)
		(legacy_teardrops no)
	)
	(paper "A4")
	(title_block
		(title "04192023_DAF0TMB3IC0_F0TG_MB_C_brd_V02_OCP.brd")
		(comment 1 "Grand Teton / footprints 4776-4778 of 8354")
	)
	(layers
		(0 "F.Cu" signal "TOP")
		(4 "In1.Cu" signal "GND")
		(6 "In2.Cu" signal "IN1")
		(8 "In3.Cu" signal "GND1")
		(10 "In4.Cu" signal "IN2")
		(12 "In5.Cu" signal "GND2")
		(14 "In6.Cu" signal "IN3")
		(16 "In7.Cu" signal "GND3")
		(18 "In8.Cu" signal "VCC")
		(20 "In9.Cu" signal "VCC1")
		(22 "In10.Cu" signal "GND4")
		(24 "In11.Cu" signal "IN4")
		(26 "In12.Cu" signal "GND5")
		(28 "In13.Cu" signal "IN5")
		(30 "In14.Cu" signal "GND6")
		(32 "In15.Cu" signal "IN6")
		(34 "In16.Cu" signal "GND7")
		(2 "B.Cu" signal "BOTTOM")
		(9 "F.Adhes" user "F.Adhesive")
		(11 "B.Adhes" user "B.Adhesive")
		(13 "F.Paste" user "Package Geometry/Pastemask Top")
		(15 "B.Paste" user "Package Geometry/Pastemask Bottom")
		(5 "F.SilkS" user "Ref Des/Silkscreen Top")
		(7 "B.SilkS" user "Ref Des/Silkscreen Bottom")
		(1 "F.Mask" user "Board Geometry/Soldermask Top")
		(3 "B.Mask" user "Board Geometry/Soldermask Bottom")
		(17 "Dwgs.User" user "User.Drawings")
		(19 "Cmts.User" user "User.Comments")
		(21 "Eco1.User" user "User.Eco1")
		(23 "Eco2.User" user "User.Eco2")
		(25 "Edge.Cuts" user "Board Geometry/Outline")
		(27 "Margin" user)
		(31 "F.CrtYd" user "Package Geometry/Place Bound Top")
		(29 "B.CrtYd" user "Package Geometry/Place Bound Bottom")
		(35 "F.Fab" user "Ref Des/Assembly Top")
		(33 "B.Fab" user "Ref Des/Assembly Bottom")
	)
	(footprint ""
		(layer "F.Cu")
		(at 109.918754 -326.566276 180)
		(property "Reference" "PR228"
			(at 0 0 180)
			(layer "F.SilkS")
			(hide yes)
			(effects
				(font
					(size 1.27 1.27)
				)
			)
		)
		(property "Value" ""
			(at 0 0 180)
			(layer "F.Fab")
			(effects
				(font
					(size 1.27 1.27)
				)
			)
		)
		(duplicate_pad_numbers_are_jumpers no)
		(fp_line
			(start 0.7874 0.4064)
			(end -0.7874 0.4064)
			(stroke
				(width 0.1524)
				(type default)
			)
			(layer "F.SilkS")
		)
		(fp_line
			(start 0.7874 -0.4064)
			(end 0.7874 0.4064)
			(stroke
				(width 0.1524)
				(type default)
			)
			(layer "F.SilkS")
		)
		(fp_line
			(start -0.7874 0.4064)
			(end -0.7874 -0.4064)
			(stroke
				(width 0.1524)
				(type default)
			)
			(layer "F.SilkS")
		)
		(fp_line
			(start -0.7874 -0.4064)
			(end 0.7874 -0.4064)
			(stroke
				(width 0.1524)
				(type default)
			)
			(layer "F.SilkS")
		)
		(fp_line
			(start 0.67945 0.3048)
			(end 0.120396 0.3048)
			(stroke
				(width 0.1)
				(type default)
			)
			(layer "F.Fab")
		)
		(fp_line
			(start 0.67945 -0.3048)
			(end 0.67945 0.3048)
			(stroke
				(width 0.1)
				(type default)
			)
			(layer "F.Fab")
		)
		(fp_line
			(start 0.12065 -0.2794)
			(end 0.12065 -0.3048)
			(stroke
				(width 0.1)
				(type default)
			)
			(layer "F.Fab")
		)
		(fp_line
			(start 0.12065 -0.3048)
			(end 0.67945 -0.3048)
			(stroke
				(width 0.1)
				(type default)
			)
			(layer "F.Fab")
		)
		(fp_line
			(start 0.120396 0.3048)
			(end 0.120396 0.2794)
			(stroke
				(width 0.1)
				(type default)
			)
			(layer "F.Fab")
		)
		(fp_line
			(start 0.120396 0.2794)
			(end -0.12065 0.2794)
			(stroke
				(width 0.1)
				(type default)
			)
			(layer "F.Fab")
		)
		(fp_line
			(start -0.12065 0.3048)
			(end -0.67945 0.3048)
			(stroke
				(width 0.1)
				(type default)
			)
			(layer "F.Fab")
		)
		(fp_line
			(start -0.12065 0.2794)
			(end -0.12065 0.3048)
			(stroke
				(width 0.1)
				(type default)
			)
			(layer "F.Fab")
		)
		(fp_line
			(start -0.12065 -0.2794)
			(end 0.12065 -0.2794)
			(stroke
				(width 0.1)
				(type default)
			)
			(layer "F.Fab")
		)
		(fp_line
			(start -0.12065 -0.305054)
			(end -0.12065 -0.2794)
			(stroke
				(width 0.1)
				(type default)
			)
			(layer "F.Fab")
		)
		(fp_line
			(start -0.67945 0.3048)
			(end -0.67945 -0.305054)
			(stroke
				(width 0.1)
				(type default)
			)
			(layer "F.Fab")
		)
		(fp_line
			(start -0.67945 -0.305054)
			(end -0.12065 -0.305054)
			(stroke
				(width 0.1)
				(type default)
			)
			(layer "F.Fab")
		)
		(pad "1" smd circle
			(at -0.40005 0 180)
			(size 0 0)
			(layers "F.Cu" "F.Mask" "F.Paste")
			(net "VSENSE_PVDDCR_CPU1_P1_DP")
		)
		(pad "2" smd circle
			(at 0.40005 0 180)
			(size 0 0)
			(layers "F.Cu" "F.Mask" "F.Paste")
			(net "PVDDCR_CPU1_P1")
		)
	)
	(footprint ""
		(layer "F.Cu")
		(at 177.40757 -425.304966)
		(property "Reference" "R2982"
			(at 0 0 0)
			(layer "F.SilkS")
			(hide yes)
			(effects
				(font
					(size 1.27 1.27)
				)
			)
		)
		(property "Value" ""
			(at 0 0 0)
			(layer "F.Fab")
			(effects
				(font
					(size 1.27 1.27)
				)
			)
		)
		(duplicate_pad_numbers_are_jumpers no)
		(fp_line
			(start -0.7874 -0.4064)
			(end 0.7874 -0.4064)
			(stroke
				(width 0.1524)
				(type default)
			)
			(layer "F.SilkS")
		)
		(fp_line
			(start -0.7874 0.4064)
			(end -0.7874 -0.4064)
			(stroke
				(width 0.1524)
				(type default)
			)
			(layer "F.SilkS")
		)
		(fp_line
			(start 0.7874 -0.4064)
			(end 0.7874 0.4064)
			(stroke
				(width 0.1524)
				(type default)
			)
			(layer "F.SilkS")
		)
		(fp_line
			(start 0.7874 0.4064)
			(end -0.7874 0.4064)
			(stroke
				(width 0.1524)
				(type default)
			)
			(layer "F.SilkS")
		)
		(fp_line
			(start -0.67945 -0.305054)
			(end -0.12065 -0.305054)
			(stroke
				(width 0.1)
				(type default)
			)
			(layer "F.Fab")
		)
		(fp_line
			(start -0.67945 0.3048)
			(end -0.67945 -0.305054)
			(stroke
				(width 0.1)
				(type default)
			)
			(layer "F.Fab")
		)
		(fp_line
			(start -0.12065 -0.305054)
			(end -0.12065 -0.2794)
			(stroke
				(width 0.1)
				(type default)
			)
			(layer "F.Fab")
		)
		(fp_line
			(start -0.12065 -0.2794)
			(end 0.12065 -0.2794)
			(stroke
				(width 0.1)
				(type default)
			)
			(layer "F.Fab")
		)
		(fp_line
			(start -0.12065 0.2794)
			(end -0.12065 0.3048)
			(stroke
				(width 0.1)
				(type default)
			)
			(layer "F.Fab")
		)
		(fp_line
			(start -0.12065 0.3048)
			(end -0.67945 0.3048)
			(stroke
				(width 0.1)
				(type default)
			)
			(layer "F.Fab")
		)
		(fp_line
			(start 0.120396 0.2794)
			(end -0.12065 0.2794)
			(stroke
				(width 0.1)
				(type default)
			)
			(layer "F.Fab")
		)
		(fp_line
			(start 0.120396 0.3048)
			(end 0.120396 0.2794)
			(stroke
				(width 0.1)
				(type default)
			)
			(layer "F.Fab")
		)
		(fp_line
			(start 0.12065 -0.3048)
			(end 0.67945 -0.3048)
			(stroke
				(width 0.1)
				(type default)
			)
			(layer "F.Fab")
		)
		(fp_line
			(start 0.12065 -0.2794)
			(end 0.12065 -0.3048)
			(stroke
				(width 0.1)
				(type default)
			)
			(layer "F.Fab")
		)
		(fp_line
			(start 0.67945 -0.3048)
			(end 0.67945 0.3048)
			(stroke
				(width 0.1)
				(type default)
			)
			(layer "F.Fab")
		)
		(fp_line
			(start 0.67945 0.3048)
			(end 0.120396 0.3048)
			(stroke
				(width 0.1)
				(type default)
			)
			(layer "F.Fab")
		)
		(pad "1" smd circle
			(at -0.40005 0)
			(size 0 0)
			(layers "F.Cu" "F.Mask" "F.Paste")
			(net "SMB_IOEXP_3V3AUX_SCL")
		)
		(pad "2" smd circle
			(at 0.40005 0)
			(size 0 0)
			(layers "F.Cu" "F.Mask" "F.Paste")
			(net "SMB_IOEXP_3V3AUX_SCL_R1")
		)
	)
	(footprint ""
		(layer "F.Cu")
		(at 75.7936 -383.7432)
		(property "Reference" "R791"
			(at 0 0 0)
			(layer "F.SilkS")
			(hide yes)
			(effects
				(font
					(size 1.27 1.27)
				)
			)
		)
		(property "Value" ""
			(at 0 0 0)
			(layer "F.Fab")
			(effects
				(font
					(size 1.27 1.27)
				)
			)
		)
		(duplicate_pad_numbers_are_jumpers no)
		(fp_line
			(start -0.32512 -0.175006)
			(end 0.32512 -0.175006)
			(stroke
				(width 0.1)
				(type default)
			)
			(layer "F.Fab")
		)
		(fp_line
			(start -0.32512 0.175006)
			(end -0.32512 -0.175006)
			(stroke
				(width 0.1)
				(type default)
			)
			(layer "F.Fab")
		)
		(fp_line
			(start 0.32512 -0.175006)
			(end 0.32512 0.175006)
			(stroke
				(width 0.1)
				(type default)
			)
			(layer "F.Fab")
		)
		(fp_line
			(start 0.32512 0.175006)
			(end -0.32512 0.175006)
			(stroke
				(width 0.1)
				(type default)
			)
			(layer "F.Fab")
		)
		(pad "1" smd rect
			(at -0.2667 0)
			(size 0.3048 0.381)
			(layers "F.Cu" "F.Mask" "F.Paste")
			(net "TEST2_RT_CPU1_P1")
		)
		(pad "2" smd rect
			(at 0.2667 0 180)
			(size 0.3048 0.381)
			(layers "F.Cu" "F.Mask" "F.Paste")
			(net "GND")
		)
	)
)
